# BASEBOARD_FAB2 (Tioga Pass) — schematic netlist excerpt (pin names and nets, part order shuffled) for the footprints in the layout excerpt that follows; sources: Cadence DE-HDL packaged netlist, KiCad conversion of Wiwynn_Tioga_Pass_MB.brd

RF5  RES  1.0K 0.1% CHIP  pkg 0402  page 201 : A = VR_PVCCIN_CPU0_AIREF5 ; B = ISENSE_PVCCIN_CPU0_PH5_IMON
C7E11  CAP  22UF 16V 10% X6S  pkg 1206LF  page 241 : A = VR_FET_SW_P5V_STBY_PVIN ; B = GND

(kicad_pcb
	(version 20260206)
	(generator "pcbnew")
	(generator_version "10.0")
	(general
		(thickness 1.6)
		(legacy_teardrops no)
	)
	(paper "A4")
	(title_block
		(title "Wiwynn_Tioga_Pass_MB.brd")
		(comment 1 "Tioga Pass / footprints 507-508 of 4770")
	)
	(layers
		(0 "F.Cu" signal "TOP")
		(4 "In1.Cu" signal "L2GND")
		(6 "In2.Cu" signal "L3")
		(8 "In3.Cu" signal "L4GND")
		(10 "In4.Cu" signal "L5")
		(12 "In5.Cu" signal "L6GND")
		(14 "In6.Cu" signal "L7VCC")
		(16 "In7.Cu" signal "L8VCC")
		(18 "In8.Cu" signal "L9GND")
		(20 "In9.Cu" signal "L10")
		(22 "In10.Cu" signal "L11GND")
		(24 "In11.Cu" signal "L12")
		(26 "In12.Cu" signal "L13GND")
		(2 "B.Cu" signal "BOTTOM")
		(9 "F.Adhes" user "F.Adhesive")
		(11 "B.Adhes" user "B.Adhesive")
		(13 "F.Paste" user "Package Geometry/Pastemask Top")
		(15 "B.Paste" user "Package Geometry/Pastemask Bottom")
		(5 "F.SilkS" user "Ref Des/Silkscreen Top")
		(7 "B.SilkS" user "Ref Des/Silkscreen Bottom")
		(1 "F.Mask" user "Board Geometry/Soldermask Top")
		(3 "B.Mask" user "Board Geometry/Soldermask Bottom")
		(17 "Dwgs.User" user "User.Drawings")
		(19 "Cmts.User" user "User.Comments")
		(21 "Eco1.User" user "User.Eco1")
		(23 "Eco2.User" user "User.Eco2")
		(25 "Edge.Cuts" user "Board Geometry/Outline")
		(27 "Margin" user)
		(31 "F.CrtYd" user "Package Geometry/Place Bound Top")
		(29 "B.CrtYd" user "Package Geometry/Place Bound Bottom")
		(35 "F.Fab" user "Ref Des/Assembly Top")
		(33 "B.Fab" user "Ref Des/Assembly Bottom")
	)
	(footprint ""
		(layer "F.Cu")
		(at 384.291586 -67.6656 180)
		(property "Reference" "C7E11"
			(at 0 0 180)
			(layer "F.SilkS")
			(hide yes)
			(effects
				(font
					(size 1.27 1.27)
				)
			)
		)
		(property "Value" ""
			(at 0 0 180)
			(layer "F.Fab")
			(effects
				(font
					(size 1.27 1.27)
				)
			)
		)
		(duplicate_pad_numbers_are_jumpers no)
		(fp_line
			(start 0.9017 1.953768)
			(end 0.9017 0.824484)
			(stroke
				(width 0.1524)
				(type default)
			)
			(layer "F.SilkS")
		)
		(fp_line
			(start -0.9017 1.953006)
			(end -0.9017 0.823976)
			(stroke
				(width 0.1524)
				(type default)
			)
			(layer "F.SilkS")
		)
		(fp_poly
			(pts
				(xy -0.9017 -0.3048) (xy 0.9017 -0.3048) (xy 0.9017 3.0988) (xy -0.9017 3.0988)
			)
			(stroke
				(width 0)
				(type default)
			)
			(fill no)
			(layer "F.CrtYd")
		)
		(fp_line
			(start 0.9017 3.0988)
			(end 0.9017 -0.3048)
			(stroke
				(width 0.1)
				(type default)
			)
			(layer "F.Fab")
		)
		(fp_line
			(start 0.9017 -0.3048)
			(end -0.9017 -0.3048)
			(stroke
				(width 0.1)
				(type default)
			)
			(layer "F.Fab")
		)
		(fp_line
			(start -0.9017 3.0988)
			(end 0.9017 3.0988)
			(stroke
				(width 0.1)
				(type default)
			)
			(layer "F.Fab")
		)
		(fp_line
			(start -0.9017 -0.3048)
			(end -0.9017 3.0988)
			(stroke
				(width 0.1)
				(type default)
			)
			(layer "F.Fab")
		)
		(pad "1" smd rect
			(at 0 0 180)
			(size 1.524 1.016)
			(layers "F.Cu" "F.Mask" "F.Paste")
			(net "VR_FET_SW_P5V_STBY_PVIN")
		)
		(pad "2" smd rect
			(at 0 2.794 180)
			(size 1.524 1.016)
			(layers "F.Cu" "F.Mask" "F.Paste")
			(net "GND")
		)
		(zone
			(layer "F.Cu")
			(hatch none 0.5)
			(connect_pads
				(clearance 0)
			)
			(min_thickness 0.25)
			(keepout
				(tracks allowed)
				(vias not_allowed)
				(pads allowed)
				(copperpour not_allowed)
				(footprints allowed)
			)
			(placement
				(enabled no)
				(sheetname "")
			)
			(fill
				(thermal_gap 0.5)
				(thermal_bridge_width 0.5)
				(island_removal_mode 0)
			)
			(polygon
				(pts
					(xy 383.529586 -68.1736) (xy 383.529586 -69.9516) (xy 385.053586 -69.9516) (xy 385.053586 -68.1736)
				)
			)
		)
	)
	(footprint ""
		(layer "F.Cu")
		(at 188.5696 -70.5739 180)
		(property "Reference" "RF5"
			(at -0.8382 -0.67818 180)
			(unlocked yes)
			(layer "F.SilkS")
			(effects
				(font
					(size 0.4064 0.254)
					(thickness 0.1524)
				)
				(justify left)
			)
		)
		(property "Value" ""
			(at 0 0 180)
			(layer "F.Fab")
			(effects
				(font
					(size 1.27 1.27)
				)
			)
		)
		(duplicate_pad_numbers_are_jumpers no)
		(fp_poly
			(pts
				(xy -0.2794 -0.1016) (xy 0.2794 -0.1016) (xy 0.2794 0.9906) (xy -0.2794 0.9906)
			)
			(stroke
				(width 0)
				(type default)
			)
			(fill no)
			(layer "F.CrtYd")
		)
		(fp_line
			(start 0.2794 0.9906)
			(end 0.2794 -0.1016)
			(stroke
				(width 0.1)
				(type default)
			)
			(layer "F.Fab")
		)
		(fp_line
			(start 0.2794 -0.1016)
			(end -0.2794 -0.1016)
			(stroke
				(width 0.1)
				(type default)
			)
			(layer "F.Fab")
		)
		(fp_line
			(start -0.2794 0.9906)
			(end 0.2794 0.9906)
			(stroke
				(width 0.1)
				(type default)
			)
			(layer "F.Fab")
		)
		(fp_line
			(start -0.2794 -0.1016)
			(end -0.2794 0.9906)
			(stroke
				(width 0.1)
				(type default)
			)
			(layer "F.Fab")
		)
		(pad "1" smd rect
			(at 0 0 180)
			(size 0.508 0.508)
			(layers "F.Cu" "F.Mask" "F.Paste")
			(net "VR_PVCCIN_CPU0_AIREF5")
		)
		(pad "2" smd rect
			(at 0 0.889 180)
			(size 0.508 0.508)
			(layers "F.Cu" "F.Mask" "F.Paste")
			(net "ISENSE_PVCCIN_CPU0_PH5_IMON")
		)
		(zone
			(layer "F.Cu")
			(hatch none 0.5)
			(connect_pads
				(clearance 0)
			)
			(min_thickness 0.25)
			(keepout
				(tracks not_allowed)
				(vias allowed)
				(pads allowed)
				(copperpour not_allowed)
				(footprints allowed)
			)
			(placement
				(enabled no)
				(sheetname "")
			)
			(fill
				(thermal_gap 0.5)
				(thermal_bridge_width 0.5)
				(island_removal_mode 0)
			)
			(polygon
				(pts
					(xy 188.8236 -71.2089) (xy 188.3156 -71.2089) (xy 188.3156 -70.8279) (xy 188.8236 -70.8279)
				)
			)
		)
		(zone
			(layer "F.Cu")
			(hatch none 0.5)
			(connect_pads
				(clearance 0)
			)
			(min_thickness 0.25)
			(keepout
				(tracks allowed)
				(vias not_allowed)
				(pads allowed)
				(copperpour not_allowed)
				(footprints allowed)
			)
			(placement
				(enabled no)
				(sheetname "")
			)
			(fill
				(thermal_gap 0.5)
				(thermal_bridge_width 0.5)
				(island_removal_mode 0)
			)
			(polygon
				(pts
					(xy 188.8236 -70.8279) (xy 188.3156 -70.8279) (xy 188.3156 -71.2089) (xy 188.8236 -71.2089)
				)
			)
		)
	)
)
